(kicad_pcb
	(version 20260206)
	(generator "pcbnew")
	(generator_version "10.0")
	(general
		(thickness 1.6)
		(legacy_teardrops no)
	)
	(paper "A4")
	(title_block
		(title "04192023_DAF0TMB3IC0_F0TG_MB_C_brd_V02_OCP.brd")
		(comment 1 "Grand Teton / footprints 2042-2048 of 8354")
	)
	(layers
		(0 "F.Cu" signal "TOP")
		(4 "In1.Cu" signal "GND")
		(6 "In2.Cu" signal "IN1")
		(8 "In3.Cu" signal "GND1")
		(10 "In4.Cu" signal "IN2")
		(12 "In5.Cu" signal "GND2")
		(14 "In6.Cu" signal "IN3")
		(16 "In7.Cu" signal "GND3")
		(18 "In8.Cu" signal "VCC")
		(20 "In9.Cu" signal "VCC1")
		(22 "In10.Cu" signal "GND4")
		(24 "In11.Cu" signal "IN4")
		(26 "In12.Cu" signal "GND5")
		(28 "In13.Cu" signal "IN5")
		(30 "In14.Cu" signal "GND6")
		(32 "In15.Cu" signal "IN6")
		(34 "In16.Cu" signal "GND7")
		(2 "B.Cu" signal "BOTTOM")
		(9 "F.Adhes" user "F.Adhesive")
		(11 "B.Adhes" user "B.Adhesive")
		(13 "F.Paste" user "Package Geometry/Pastemask Top")
		(15 "B.Paste" user "Package Geometry/Pastemask Bottom")
		(5 "F.SilkS" user "Ref Des/Silkscreen Top")
		(7 "B.SilkS" user "Ref Des/Silkscreen Bottom")
		(1 "F.Mask" user "Board Geometry/Soldermask Top")
		(3 "B.Mask" user "Board Geometry/Soldermask Bottom")
		(17 "Dwgs.User" user "User.Drawings")
		(19 "Cmts.User" user "User.Comments")
		(21 "Eco1.User" user "User.Eco1")
		(23 "Eco2.User" user "User.Eco2")
		(25 "Edge.Cuts" user "Board Geometry/Outline")
		(27 "Margin" user)
		(31 "F.CrtYd" user "Package Geometry/Place Bound Top")
		(29 "B.CrtYd" user "Package Geometry/Place Bound Bottom")
		(35 "F.Fab" user "Ref Des/Assembly Top")
		(33 "B.Fab" user "Ref Des/Assembly Bottom")
	)
	(footprint ""
		(layer "F.Cu")
		(at 215.646 -99.822)
		(property "Reference" "U9002"
			(at -0.88519 -1.39446 90)
			(unlocked yes)
			(layer "F.SilkS")
			(effects
				(font
					(size 0.7874 0.5842)
					(thickness 0.1524)
				)
				(justify left)
			)
		)
		(property "Value" ""
			(at 0 0 0)
			(layer "F.Fab")
			(effects
				(font
					(size 1.27 1.27)
				)
			)
		)
		(duplicate_pad_numbers_are_jumpers no)
		(fp_line
			(start -1.4986 -1.100074)
			(end 1.4986 -1.100074)
			(stroke
				(width 0.1524)
				(type default)
			)
			(layer "F.SilkS")
		)
		(fp_line
			(start -1.4986 1.100074)
			(end -1.4986 -1.100074)
			(stroke
				(width 0.1524)
				(type default)
			)
			(layer "F.SilkS")
		)
		(fp_line
			(start 1.4986 -1.100074)
			(end 1.4986 1.100074)
			(stroke
				(width 0.1524)
				(type default)
			)
			(layer "F.SilkS")
		)
		(fp_line
			(start 1.4986 1.100074)
			(end -1.4986 1.100074)
			(stroke
				(width 0.1524)
				(type default)
			)
			(layer "F.SilkS")
		)
		(fp_poly
			(pts
				(xy -2.378456 -0.7366) (xy -2.169922 -1.325372) (xy -1.757426 -0.831342)
			)
			(stroke
				(width 0)
				(type default)
			)
			(fill yes)
			(layer "F.SilkS")
		)
		(fp_line
			(start -0.67437 -1.100074)
			(end 0.67437 -1.100074)
			(stroke
				(width 0.1)
				(type default)
			)
			(layer "F.Fab")
		)
		(fp_line
			(start -0.67437 1.100074)
			(end -0.67437 -1.100074)
			(stroke
				(width 0.1)
				(type default)
			)
			(layer "F.Fab")
		)
		(fp_line
			(start 0.67437 -1.100074)
			(end 0.67437 1.100074)
			(stroke
				(width 0.1)
				(type default)
			)
			(layer "F.Fab")
		)
		(fp_line
			(start 0.67437 1.100074)
			(end -0.67437 1.100074)
			(stroke
				(width 0.1)
				(type default)
			)
			(layer "F.Fab")
		)
		(fp_poly
			(pts
				(xy -2.20472 -0.338328) (xy -2.20472 -0.963168) (xy -1.651 -0.635)
			)
			(stroke
				(width 0)
				(type default)
			)
			(fill yes)
			(layer "F.Fab")
		)
		(pad "1" smd rect
			(at -0.889 -0.649986)
			(size 1.016 0.381)
			(layers "F.Cu" "F.Mask" "F.Paste")
			(net "HP_LVC3_OCP_V3_1_PWRGD_R1")
		)
		(pad "2" smd rect
			(at -0.889 0)
			(size 1.016 0.381)
			(layers "F.Cu" "F.Mask" "F.Paste")
			(net "FM_PLD_OCP_SFF_AUX_PWR_EN")
		)
		(pad "3" smd rect
			(at -0.889 0.649986)
			(size 1.016 0.381)
			(layers "F.Cu" "F.Mask" "F.Paste")
			(net "GND")
		)
		(pad "4" smd rect
			(at 0.889 0.649986)
			(size 1.016 0.381)
			(layers "F.Cu" "F.Mask" "F.Paste")
			(net "OCP_SFF_AUX_PWR_EN_R3")
		)
		(pad "5" smd rect
			(at 0.889 -0.649986)
			(size 1.016 0.381)
			(layers "F.Cu" "F.Mask" "F.Paste")
			(net "P3V3_AUX")
		)
	)
	(footprint ""
		(layer "F.Cu")
		(at 415.459164 -17.624298 90)
		(property "Reference" "C1566"
			(at 0 0 90)
			(layer "F.SilkS")
			(hide yes)
			(effects
				(font
					(size 1.27 1.27)
				)
			)
		)
		(property "Value" ""
			(at 0 0 90)
			(layer "F.Fab")
			(effects
				(font
					(size 1.27 1.27)
				)
			)
		)
		(duplicate_pad_numbers_are_jumpers no)
		(fp_line
			(start 0.299974 -0.150114)
			(end 0.299974 0.150114)
			(stroke
				(width 0.1)
				(type default)
			)
			(layer "F.Fab")
		)
		(fp_line
			(start -0.299974 -0.150114)
			(end 0.299974 -0.150114)
			(stroke
				(width 0.1)
				(type default)
			)
			(layer "F.Fab")
		)
		(fp_line
			(start 0.299974 0.150114)
			(end -0.299974 0.150114)
			(stroke
				(width 0.1)
				(type default)
			)
			(layer "F.Fab")
		)
		(fp_line
			(start -0.299974 0.150114)
			(end -0.299974 -0.150114)
			(stroke
				(width 0.1)
				(type default)
			)
			(layer "F.Fab")
		)
		(pad "1" smd rect
			(at -0.2667 0 90)
			(size 0.3048 0.381)
			(layers "F.Cu" "F.Mask" "F.Paste")
			(net "P5E_CPU0_G3_TX_C_DN<6>")
		)
		(pad "2" smd rect
			(at 0.2667 0 90)
			(size 0.3048 0.381)
			(layers "F.Cu" "F.Mask" "F.Paste")
			(net "P5E_CPU0_G3_TX_DN<6>")
		)
	)
	(footprint ""
		(layer "F.Cu")
		(at 142.367 -117.475 180)
		(property "Reference" "U8010"
			(at 4.572 1.37033 0)
			(unlocked yes)
			(layer "F.SilkS")
			(effects
				(font
					(size 0.7874 0.5842)
					(thickness 0.1524)
				)
			)
		)
		(property "Value" ""
			(at 0 0 180)
			(layer "F.Fab")
			(effects
				(font
					(size 1.27 1.27)
				)
			)
		)
		(duplicate_pad_numbers_are_jumpers no)
		(fp_line
			(start 2.032 1.549908)
			(end -2.032 1.549908)
			(stroke
				(width 0.1524)
				(type default)
			)
			(layer "F.SilkS")
		)
		(fp_line
			(start 2.032 -1.549908)
			(end 2.032 1.549908)
			(stroke
				(width 0.1524)
				(type default)
			)
			(layer "F.SilkS")
		)
		(fp_line
			(start 0.508 -1.549908)
			(end 2.032 -1.549908)
			(stroke
				(width 0.1524)
				(type default)
			)
			(layer "F.SilkS")
		)
		(fp_line
			(start 0 -0.762)
			(end 0.508 -1.549908)
			(stroke
				(width 0.1524)
				(type default)
			)
			(layer "F.SilkS")
		)
		(fp_line
			(start -0.508 -1.549908)
			(end 0 -0.762)
			(stroke
				(width 0.1524)
				(type default)
			)
			(layer "F.SilkS")
		)
		(fp_line
			(start -2.032 1.549908)
			(end -2.032 -1.549908)
			(stroke
				(width 0.1524)
				(type default)
			)
			(layer "F.SilkS")
		)
		(fp_line
			(start -2.032 -1.549908)
			(end -0.508 -1.549908)
			(stroke
				(width 0.1524)
				(type default)
			)
			(layer "F.SilkS")
		)
		(fp_poly
			(pts
				(xy -4.349496 -1.589024) (xy -4.349496 -0.573024) (xy -3.333496 -1.081024)
			)
			(stroke
				(width 0)
				(type default)
			)
			(fill yes)
			(layer "F.SilkS")
		)
		(fp_line
			(start 0.849884 1.549908)
			(end -0.849884 1.549908)
			(stroke
				(width 0.1)
				(type default)
			)
			(layer "F.Fab")
		)
		(fp_line
			(start 0.849884 -1.549908)
			(end 0.849884 1.549908)
			(stroke
				(width 0.1)
				(type default)
			)
			(layer "F.Fab")
		)
		(fp_line
			(start -0.849884 1.549908)
			(end -0.849884 -1.549908)
			(stroke
				(width 0.1)
				(type default)
			)
			(layer "F.Fab")
		)
		(fp_line
			(start -0.849884 -1.549908)
			(end 0.849884 -1.549908)
			(stroke
				(width 0.1)
				(type default)
			)
			(layer "F.Fab")
		)
		(fp_poly
			(pts
				(xy -3.2004 -1.45796) (xy -3.2004 -0.44196) (xy -2.1844 -0.94996)
			)
			(stroke
				(width 0)
				(type default)
			)
			(fill yes)
			(layer "F.Fab")
		)
		(pad "1" smd rect
			(at -1.35001 -0.94996 90)
			(size 0.6096 1.0668)
			(layers "F.Cu" "F.Mask" "F.Paste")
			(net "UV_P2V5_COMP")
		)
		(pad "2" smd rect
			(at -1.35001 0 90)
			(size 0.6096 1.0668)
			(layers "F.Cu" "F.Mask" "F.Paste")
			(net "GND")
		)
		(pad "3" smd rect
			(at -1.35001 0.94996 90)
			(size 0.6096 1.0668)
			(layers "F.Cu" "F.Mask" "F.Paste")
			(net "P12V_AUX_UV_TRIGGER")
		)
		(pad "4" smd rect
			(at 1.35001 0.94996 90)
			(size 0.6096 1.0668)
			(layers "F.Cu" "F.Mask" "F.Paste")
			(net "IRQ_UV_DETECT_R2_N")
		)
		(pad "5" smd rect
			(at 1.35001 -0.94996 90)
			(size 0.6096 1.0668)
			(layers "F.Cu" "F.Mask" "F.Paste")
			(net "P12V_AUX")
		)
	)
	(footprint ""
		(layer "F.Cu")
		(at 229.0191 -304.162206 90)
		(property "Reference" "PL6502"
			(at -7.4422 -7.254748 90)
			(unlocked yes)
			(layer "F.SilkS")
			(effects
				(font
					(size 0.7874 0.5842)
					(thickness 0.1524)
				)
				(justify left)
			)
		)
		(property "Value" ""
			(at 0 0 90)
			(layer "F.Fab")
			(effects
				(font
					(size 1.27 1.27)
				)
			)
		)
		(duplicate_pad_numbers_are_jumpers no)
		(fp_line
			(start 7.4422 -6.400038)
			(end 7.4422 6.400038)
			(stroke
				(width 0.1524)
				(type default)
			)
			(layer "F.SilkS")
		)
		(fp_line
			(start -7.4422 -6.400038)
			(end 7.4422 -6.400038)
			(stroke
				(width 0.1524)
				(type default)
			)
			(layer "F.SilkS")
		)
		(fp_line
			(start 7.4422 6.400038)
			(end -7.4422 6.400038)
			(stroke
				(width 0.1524)
				(type default)
			)
			(layer "F.SilkS")
		)
		(fp_line
			(start -7.4422 6.400038)
			(end -7.4422 -6.400038)
			(stroke
				(width 0.1524)
				(type default)
			)
			(layer "F.SilkS")
		)
		(fp_line
			(start 6.938264 -6.400038)
			(end -6.862064 -6.400038)
			(stroke
				(width 0.1)
				(type default)
			)
			(layer "F.Fab")
		)
		(fp_line
			(start -6.862064 -6.400038)
			(end -6.862064 6.400038)
			(stroke
				(width 0.1)
				(type default)
			)
			(layer "F.Fab")
		)
		(fp_line
			(start 6.938264 6.400038)
			(end 6.938264 -6.400038)
			(stroke
				(width 0.1)
				(type default)
			)
			(layer "F.Fab")
		)
		(fp_line
			(start -6.862064 6.400038)
			(end 6.938264 6.400038)
			(stroke
				(width 0.1)
				(type default)
			)
			(layer "F.Fab")
		)
		(pad "1" smd rect
			(at -5.650484 0 90)
			(size 3.302 4.29768)
			(layers "F.Cu" "F.Mask" "F.Paste")
			(net "SW_P1V8_RETIMER_CPU1_SW")
		)
		(pad "2" smd rect
			(at 5.650484 0 90)
			(size 3.302 4.29768)
			(layers "F.Cu" "F.Mask" "F.Paste")
			(net "P1V8_CPU1_RT_1D")
		)
	)
	(footprint ""
		(layer "F.Cu")
		(at 76.654914 -172.76826 -90)
		(property "Reference" "PC306_5"
			(at 0 0 270)
			(layer "F.SilkS")
			(hide yes)
			(effects
				(font
					(size 1.27 1.27)
				)
			)
		)
		(property "Value" ""
			(at 0 0 270)
			(layer "F.Fab")
			(effects
				(font
					(size 1.27 1.27)
				)
			)
		)
		(duplicate_pad_numbers_are_jumpers no)
		(fp_line
			(start -0.7874 0.4064)
			(end -0.7874 -0.4064)
			(stroke
				(width 0.1524)
				(type default)
			)
			(layer "F.SilkS")
		)
		(fp_line
			(start 0.7874 0.4064)
			(end -0.7874 0.4064)
			(stroke
				(width 0.1524)
				(type default)
			)
			(layer "F.SilkS")
		)
		(fp_line
			(start -0.7874 -0.4064)
			(end 0.7874 -0.4064)
			(stroke
				(width 0.1524)
				(type default)
			)
			(layer "F.SilkS")
		)
		(fp_line
			(start 0.7874 -0.4064)
			(end 0.7874 0.4064)
			(stroke
				(width 0.1524)
				(type default)
			)
			(layer "F.SilkS")
		)
		(fp_line
			(start -0.67945 0.3048)
			(end -0.67945 -0.305054)
			(stroke
				(width 0.1)
				(type default)
			)
			(layer "F.Fab")
		)
		(fp_line
			(start -0.12065 0.3048)
			(end -0.67945 0.3048)
			(stroke
				(width 0.1)
				(type default)
			)
			(layer "F.Fab")
		)
		(fp_line
			(start 0.120396 0.3048)
			(end 0.120396 0.2794)
			(stroke
				(width 0.1)
				(type default)
			)
			(layer "F.Fab")
		)
		(fp_line
			(start 0.67945 0.3048)
			(end 0.120396 0.3048)
			(stroke
				(width 0.1)
				(type default)
			)
			(layer "F.Fab")
		)
		(fp_line
			(start -0.12065 0.2794)
			(end -0.12065 0.3048)
			(stroke
				(width 0.1)
				(type default)
			)
			(layer "F.Fab")
		)
		(fp_line
			(start 0.120396 0.2794)
			(end -0.12065 0.2794)
			(stroke
				(width 0.1)
				(type default)
			)
			(layer "F.Fab")
		)
		(fp_line
			(start -0.12065 -0.2794)
			(end 0.12065 -0.2794)
			(stroke
				(width 0.1)
				(type default)
			)
			(layer "F.Fab")
		)
		(fp_line
			(start 0.12065 -0.2794)
			(end 0.12065 -0.3048)
			(stroke
				(width 0.1)
				(type default)
			)
			(layer "F.Fab")
		)
		(fp_line
			(start 0.12065 -0.3048)
			(end 0.67945 -0.3048)
			(stroke
				(width 0.1)
				(type default)
			)
			(layer "F.Fab")
		)
		(fp_line
			(start 0.67945 -0.3048)
			(end 0.67945 0.3048)
			(stroke
				(width 0.1)
				(type default)
			)
			(layer "F.Fab")
		)
		(fp_line
			(start -0.67945 -0.305054)
			(end -0.12065 -0.305054)
			(stroke
				(width 0.1)
				(type default)
			)
			(layer "F.Fab")
		)
		(fp_line
			(start -0.12065 -0.305054)
			(end -0.12065 -0.2794)
			(stroke
				(width 0.1)
				(type default)
			)
			(layer "F.Fab")
		)
		(pad "1" smd circle
			(at -0.40005 0 270)
			(size 0 0)
			(layers "F.Cu" "F.Mask" "F.Paste")
			(net "PVDDCR_CPU0_P1_VCCS")
		)
		(pad "2" smd circle
			(at 0.40005 0 270)
			(size 0 0)
			(layers "F.Cu" "F.Mask" "F.Paste")
			(net "GND")
		)
	)
	(footprint ""
		(layer "F.Cu")
		(at 94.375732 -185.680096)
		(property "Reference" "PC173"
			(at 0 0 0)
			(layer "F.SilkS")
			(hide yes)
			(effects
				(font
					(size 1.27 1.27)
				)
			)
		)
		(property "Value" ""
			(at 0 0 0)
			(layer "F.Fab")
			(effects
				(font
					(size 1.27 1.27)
				)
			)
		)
		(duplicate_pad_numbers_are_jumpers no)
		(fp_line
			(start -0.7874 -0.4064)
			(end 0.7874 -0.4064)
			(stroke
				(width 0.1524)
				(type default)
			)
			(layer "F.SilkS")
		)
		(fp_line
			(start -0.7874 0.4064)
			(end -0.7874 -0.4064)
			(stroke
				(width 0.1524)
				(type default)
			)
			(layer "F.SilkS")
		)
		(fp_line
			(start 0.7874 -0.4064)
			(end 0.7874 0.4064)
			(stroke
				(width 0.1524)
				(type default)
			)
			(layer "F.SilkS")
		)
		(fp_line
			(start 0.7874 0.4064)
			(end -0.7874 0.4064)
			(stroke
				(width 0.1524)
				(type default)
			)
			(layer "F.SilkS")
		)
		(fp_line
			(start -0.67945 -0.305054)
			(end -0.12065 -0.305054)
			(stroke
				(width 0.1)
				(type default)
			)
			(layer "F.Fab")
		)
		(fp_line
			(start -0.67945 0.3048)
			(end -0.67945 -0.305054)
			(stroke
				(width 0.1)
				(type default)
			)
			(layer "F.Fab")
		)
		(fp_line
			(start -0.12065 -0.305054)
			(end -0.12065 -0.2794)
			(stroke
				(width 0.1)
				(type default)
			)
			(layer "F.Fab")
		)
		(fp_line
			(start -0.12065 -0.2794)
			(end 0.12065 -0.2794)
			(stroke
				(width 0.1)
				(type default)
			)
			(layer "F.Fab")
		)
		(fp_line
			(start -0.12065 0.2794)
			(end -0.12065 0.3048)
			(stroke
				(width 0.1)
				(type default)
			)
			(layer "F.Fab")
		)
		(fp_line
			(start -0.12065 0.3048)
			(end -0.67945 0.3048)
			(stroke
				(width 0.1)
				(type default)
			)
			(layer "F.Fab")
		)
		(fp_line
			(start 0.120396 0.2794)
			(end -0.12065 0.2794)
			(stroke
				(width 0.1)
				(type default)
			)
			(layer "F.Fab")
		)
		(fp_line
			(start 0.120396 0.3048)
			(end 0.120396 0.2794)
			(stroke
				(width 0.1)
				(type default)
			)
			(layer "F.Fab")
		)
		(fp_line
			(start 0.12065 -0.3048)
			(end 0.67945 -0.3048)
			(stroke
				(width 0.1)
				(type default)
			)
			(layer "F.Fab")
		)
		(fp_line
			(start 0.12065 -0.2794)
			(end 0.12065 -0.3048)
			(stroke
				(width 0.1)
				(type default)
			)
			(layer "F.Fab")
		)
		(fp_line
			(start 0.67945 -0.3048)
			(end 0.67945 0.3048)
			(stroke
				(width 0.1)
				(type default)
			)
			(layer "F.Fab")
		)
		(fp_line
			(start 0.67945 0.3048)
			(end 0.120396 0.3048)
			(stroke
				(width 0.1)
				(type default)
			)
			(layer "F.Fab")
		)
		(pad "1" smd circle
			(at -0.40005 0)
			(size 0 0)
			(layers "F.Cu" "F.Mask" "F.Paste")
			(net "SW_PVDDCR_CPU0_P1_SW2")
		)
		(pad "2" smd circle
			(at 0.40005 0)
			(size 0 0)
			(layers "F.Cu" "F.Mask" "F.Paste")
			(net "SW_PVDDCR_CPU0_P1_SW2_RC")
		)
	)
	(footprint ""
		(layer "F.Cu")
		(at 288.26587 -97.967292)
		(property "Reference" "C1511"
			(at 0 0 0)
			(layer "F.SilkS")
			(hide yes)
			(effects
				(font
					(size 1.27 1.27)
				)
			)
		)
		(property "Value" ""
			(at 0 0 0)
			(layer "F.Fab")
			(effects
				(font
					(size 1.27 1.27)
				)
			)
		)
		(duplicate_pad_numbers_are_jumpers no)
		(fp_line
			(start -0.7874 -0.4064)
			(end 0.7874 -0.4064)
			(stroke
				(width 0.1524)
				(type default)
			)
			(layer "F.SilkS")
		)
		(fp_line
			(start -0.7874 0.4064)
			(end -0.7874 -0.4064)
			(stroke
				(width 0.1524)
				(type default)
			)
			(layer "F.SilkS")
		)
		(fp_line
			(start 0.7874 -0.4064)
			(end 0.7874 0.4064)
			(stroke
				(width 0.1524)
				(type default)
			)
			(layer "F.SilkS")
		)
		(fp_line
			(start 0.7874 0.4064)
			(end -0.7874 0.4064)
			(stroke
				(width 0.1524)
				(type default)
			)
			(layer "F.SilkS")
		)
		(fp_line
			(start -0.67945 -0.305054)
			(end -0.12065 -0.305054)
			(stroke
				(width 0.1)
				(type default)
			)
			(layer "F.Fab")
		)
		(fp_line
			(start -0.67945 0.3048)
			(end -0.67945 -0.305054)
			(stroke
				(width 0.1)
				(type default)
			)
			(layer "F.Fab")
		)
		(fp_line
			(start -0.12065 -0.305054)
			(end -0.12065 -0.2794)
			(stroke
				(width 0.1)
				(type default)
			)
			(layer "F.Fab")
		)
		(fp_line
			(start -0.12065 -0.2794)
			(end 0.12065 -0.2794)
			(stroke
				(width 0.1)
				(type default)
			)
			(layer "F.Fab")
		)
		(fp_line
			(start -0.12065 0.2794)
			(end -0.12065 0.3048)
			(stroke
				(width 0.1)
				(type default)
			)
			(layer "F.Fab")
		)
		(fp_line
			(start -0.12065 0.3048)
			(end -0.67945 0.3048)
			(stroke
				(width 0.1)
				(type default)
			)
			(layer "F.Fab")
		)
		(fp_line
			(start 0.120396 0.2794)
			(end -0.12065 0.2794)
			(stroke
				(width 0.1)
				(type default)
			)
			(layer "F.Fab")
		)
		(fp_line
			(start 0.120396 0.3048)
			(end 0.120396 0.2794)
			(stroke
				(width 0.1)
				(type default)
			)
			(layer "F.Fab")
		)
		(fp_line
			(start 0.12065 -0.3048)
			(end 0.67945 -0.3048)
			(stroke
				(width 0.1)
				(type default)
			)
			(layer "F.Fab")
		)
		(fp_line
			(start 0.12065 -0.2794)
			(end 0.12065 -0.3048)
			(stroke
				(width 0.1)
				(type default)
			)
			(layer "F.Fab")
		)
		(fp_line
			(start 0.67945 -0.3048)
			(end 0.67945 0.3048)
			(stroke
				(width 0.1)
				(type default)
			)
			(layer "F.Fab")
		)
		(fp_line
			(start 0.67945 0.3048)
			(end 0.120396 0.3048)
			(stroke
				(width 0.1)
				(type default)
			)
			(layer "F.Fab")
		)
		(pad "1" smd circle
			(at -0.40005 0)
			(size 0 0)
			(layers "F.Cu" "F.Mask" "F.Paste")
			(net "JTAG_TRST_N")
		)
		(pad "2" smd circle
			(at 0.40005 0)
			(size 0 0)
			(layers "F.Cu" "F.Mask" "F.Paste")
			(net "GND")
		)
	)
)
